# TIMECARD (Time Appliance Project (Time Card)) — schematic netlist excerpt (pin names and nets, part order shuffled) for the footprints in the layout excerpt that follows; sources: Cadence DE-HDL packaged netlist, KiCad conversion of R4006-B0001-02_R01.brd

R303  RESISTOR  1KOHM 1%  pkg SMC_0402R_H016  page 20 : \1\ = UNNAMED_9_BNO080LGA28_I29_PS1 ; \2\ = SG
R129  RESISTOR  0OHM -  pkg SMC_0402R_H016  page 24 : \1\ = FT_USB_DP ; \2\ = R_FT_USB_DP

(kicad_pcb
	(version 20260206)
	(generator "pcbnew")
	(generator_version "10.0")
	(general
		(thickness 1.6)
		(legacy_teardrops no)
	)
	(paper "A4")
	(title_block
		(title "timecard-production-celestica-r4006 — R4006-B0001-02_R01.brd")
		(comment 1 "Time Appliance Project (Time Card) / footprints 582-583 of 1113")
	)
	(layers
		(0 "F.Cu" signal "TOP")
		(4 "In1.Cu" signal "L02_GND1")
		(6 "In2.Cu" signal "L03_SIG1")
		(8 "In3.Cu" signal "L04_GND2")
		(10 "In4.Cu" signal "L05_VCC1")
		(12 "In5.Cu" signal "L06_VCC2")
		(14 "In6.Cu" signal "L07_GND3")
		(16 "In7.Cu" signal "L08_SIG2")
		(18 "In8.Cu" signal "L09_GND4")
		(2 "B.Cu" signal "BOTTOM")
		(9 "F.Adhes" user "F.Adhesive")
		(11 "B.Adhes" user "B.Adhesive")
		(13 "F.Paste" user "Package Geometry/Pastemask Top")
		(15 "B.Paste" user "Package Geometry/Pastemask Bottom")
		(5 "F.SilkS" user "Ref Des/Silkscreen Top")
		(7 "B.SilkS" user "Ref Des/Silkscreen Bottom")
		(1 "F.Mask" user "Board Geometry/Soldermask Top")
		(3 "B.Mask" user "Board Geometry/Soldermask Bottom")
		(17 "Dwgs.User" user "User.Drawings")
		(19 "Cmts.User" user "User.Comments")
		(21 "Eco1.User" user "User.Eco1")
		(23 "Eco2.User" user "User.Eco2")
		(25 "Edge.Cuts" user "Board Geometry/Outline")
		(27 "Margin" user)
		(31 "F.CrtYd" user "Package Geometry/Place Bound Top")
		(29 "B.CrtYd" user "Package Geometry/Place Bound Bottom")
		(35 "F.Fab" user "Ref Des/Assembly Top")
		(33 "B.Fab" user "Ref Des/Assembly Bottom")
	)
	(footprint ""
		(layer "F.Cu")
		(at 83.439 -64.3128 90)
		(property "Reference" "R303"
			(at 13.4112 -9.73963 90)
			(unlocked yes)
			(layer "F.SilkS")
			(effects
				(font
					(size 0.7874 0.5842)
					(thickness 0.1524)
				)
			)
		)
		(property "Value" "VAL*"
			(at 0.02032 2.13233 90)
			(unlocked yes)
			(layer "F.Fab")
			(hide yes)
			(effects
				(font
					(size 0.7874 0.5842)
					(thickness 0.1524)
				)
			)
		)
		(property "Device Type" "RESISTOR-G155-11001-01,1KOHM,1%"
			(at 0.008382 1.210564 90)
			(unlocked yes)
			(layer "F.Fab")
			(hide yes)
			(effects
				(font
					(size 0.7874 0.5842)
					(thickness 0.1524)
				)
			)
		)
		(property "User Part Number" "PARTNUM*"
			(at 0.02032 4.024884 90)
			(unlocked yes)
			(layer "Cmts.User")
			(hide yes)
			(effects
				(font
					(size 0.7874 0.5842)
					(thickness 0.1524)
				)
			)
		)
		(property "Tolerance" "TOL*"
			(at 0.044704 3.05435 90)
			(unlocked yes)
			(layer "Cmts.User")
			(hide yes)
			(effects
				(font
					(size 0.7874 0.5842)
					(thickness 0.1524)
				)
			)
		)
		(duplicate_pad_numbers_are_jumpers no)
		(fp_line
			(start 1.143 -0.5588)
			(end -1.143 -0.5588)
			(stroke
				(width 0.1)
				(type default)
			)
			(layer "F.SilkS")
		)
		(fp_line
			(start -1.143 -0.5588)
			(end -1.143 0.5588)
			(stroke
				(width 0.1)
				(type default)
			)
			(layer "F.SilkS")
		)
		(fp_line
			(start 1.143 0.5588)
			(end 1.143 -0.5588)
			(stroke
				(width 0.1)
				(type default)
			)
			(layer "F.SilkS")
		)
		(fp_line
			(start -1.143 0.5588)
			(end 1.143 0.5588)
			(stroke
				(width 0.1)
				(type default)
			)
			(layer "F.SilkS")
		)
		(fp_rect
			(start -1.143 -0.5588)
			(end 1.143 0.5588)
			(stroke
				(width 0)
				(type default)
			)
			(fill no)
			(layer "F.CrtYd")
		)
		(fp_line
			(start 0.508 -0.3048)
			(end -0.508 -0.3048)
			(stroke
				(width 0.1)
				(type default)
			)
			(layer "F.Fab")
		)
		(fp_line
			(start -0.508 -0.3048)
			(end -0.508 0.3048)
			(stroke
				(width 0.1)
				(type default)
			)
			(layer "F.Fab")
		)
		(fp_line
			(start 0.508 0.3048)
			(end 0.508 -0.3048)
			(stroke
				(width 0.1)
				(type default)
			)
			(layer "F.Fab")
		)
		(fp_line
			(start -0.508 0.3048)
			(end 0.508 0.3048)
			(stroke
				(width 0.1)
				(type default)
			)
			(layer "F.Fab")
		)
		(pad "1" smd rect
			(at -0.5334 0 90)
			(size 0.7112 0.6096)
			(layers "F.Cu" "F.Mask" "F.Paste")
			(net "UNNAMED_9_BNO080LGA28_I29_PS1")
		)
		(pad "2" smd rect
			(at 0.5334 0 90)
			(size 0.7112 0.6096)
			(layers "F.Cu" "F.Mask" "F.Paste")
			(net "SG")
		)
		(zone
			(layer "F.Cu")
			(hatch none 0.5)
			(connect_pads
				(clearance 0)
			)
			(min_thickness 0.25)
			(keepout
				(tracks allowed)
				(vias not_allowed)
				(pads allowed)
				(copperpour not_allowed)
				(footprints allowed)
			)
			(placement
				(enabled no)
				(sheetname "")
			)
			(fill
				(thermal_gap 0.5)
				(thermal_bridge_width 0.5)
				(island_removal_mode 0)
			)
			(polygon
				(pts
					(xy 83.1342 -64.2366) (xy 83.7438 -64.2366) (xy 83.7438 -64.389) (xy 83.1342 -64.389)
				)
			)
		)
	)
	(footprint ""
		(layer "F.Cu")
		(at 28.067 -94.234 -90)
		(property "Reference" "R129"
			(at -4.953 0.59563 90)
			(unlocked yes)
			(layer "F.SilkS")
			(effects
				(font
					(size 0.7874 0.5842)
					(thickness 0.1524)
				)
			)
		)
		(property "Value" "VAL*"
			(at 0.02032 2.13233 270)
			(unlocked yes)
			(layer "F.Fab")
			(hide yes)
			(effects
				(font
					(size 0.7874 0.5842)
					(thickness 0.1524)
				)
			)
		)
		(property "Tolerance" "TOL*"
			(at 0.044704 3.05435 270)
			(unlocked yes)
			(layer "Cmts.User")
			(hide yes)
			(effects
				(font
					(size 0.7874 0.5842)
					(thickness 0.1524)
				)
			)
		)
		(property "User Part Number" "PARTNUM*"
			(at 0.02032 4.024884 270)
			(unlocked yes)
			(layer "Cmts.User")
			(hide yes)
			(effects
				(font
					(size 0.7874 0.5842)
					(thickness 0.1524)
				)
			)
		)
		(property "Device Type" "RESISTOR-G155-100R0-J0,0OHM,-"
			(at 0.008382 1.210564 270)
			(unlocked yes)
			(layer "F.Fab")
			(hide yes)
			(effects
				(font
					(size 0.7874 0.5842)
					(thickness 0.1524)
				)
			)
		)
		(duplicate_pad_numbers_are_jumpers no)
		(fp_line
			(start -1.143 0.5588)
			(end 1.143 0.5588)
			(stroke
				(width 0.1)
				(type default)
			)
			(layer "F.SilkS")
		)
		(fp_line
			(start 1.143 0.5588)
			(end 1.143 -0.5588)
			(stroke
				(width 0.1)
				(type default)
			)
			(layer "F.SilkS")
		)
		(fp_line
			(start -1.143 -0.5588)
			(end -1.143 0.5588)
			(stroke
				(width 0.1)
				(type default)
			)
			(layer "F.SilkS")
		)
		(fp_line
			(start 1.143 -0.5588)
			(end -1.143 -0.5588)
			(stroke
				(width 0.1)
				(type default)
			)
			(layer "F.SilkS")
		)
		(fp_poly
			(pts
				(xy -1.143 0.5588) (xy 1.143 0.5588) (xy 1.143 -0.5588) (xy -1.143 -0.5588)
			)
			(stroke
				(width 0)
				(type default)
			)
			(fill no)
			(layer "F.CrtYd")
		)
		(fp_line
			(start -0.508 0.3048)
			(end 0.508 0.3048)
			(stroke
				(width 0.1)
				(type default)
			)
			(layer "F.Fab")
		)
		(fp_line
			(start 0.508 0.3048)
			(end 0.508 -0.3048)
			(stroke
				(width 0.1)
				(type default)
			)
			(layer "F.Fab")
		)
		(fp_line
			(start -0.508 -0.3048)
			(end -0.508 0.3048)
			(stroke
				(width 0.1)
				(type default)
			)
			(layer "F.Fab")
		)
		(fp_line
			(start 0.508 -0.3048)
			(end -0.508 -0.3048)
			(stroke
				(width 0.1)
				(type default)
			)
			(layer "F.Fab")
		)
		(pad "1" smd rect
			(at -0.5334 0 270)
			(size 0.7112 0.6096)
			(layers "F.Cu" "F.Mask" "F.Paste")
			(net "FT_USB_DP")
		)
		(pad "2" smd rect
			(at 0.5334 0 270)
			(size 0.7112 0.6096)
			(layers "F.Cu" "F.Mask" "F.Paste")
			(net "R_FT_USB_DP")
		)
		(zone
			(layer "F.Cu")
			(hatch none 0.5)
			(connect_pads
				(clearance 0)
			)
			(min_thickness 0.25)
			(keepout
				(tracks not_allowed)
				(vias allowed)
				(pads allowed)
				(copperpour not_allowed)
				(footprints allowed)
			)
			(placement
				(enabled no)
				(sheetname "")
			)
			(fill
				(thermal_gap 0.5)
				(thermal_bridge_width 0.5)
				(island_removal_mode 0)
			)
			(polygon
				(pts
					(xy 27.7622 -94.3102) (xy 27.7622 -94.1578) (xy 28.3718 -94.1578) (xy 28.3718 -94.3102)
				)
			)
		)
		(zone
			(layer "F.Cu")
			(hatch none 0.5)
			(connect_pads
				(clearance 0)
			)
			(min_thickness 0.25)
			(keepout
				(tracks allowed)
				(vias not_allowed)
				(pads allowed)
				(copperpour not_allowed)
				(footprints allowed)
			)
			(placement
				(enabled no)
				(sheetname "")
			)
			(fill
				(thermal_gap 0.5)
				(thermal_bridge_width 0.5)
				(island_removal_mode 0)
			)
			(polygon
				(pts
					(xy 27.7622 -94.3102) (xy 27.7622 -94.1578) (xy 28.3718 -94.1578) (xy 28.3718 -94.3102)
				)
			)
		)
	)
)
